(kicad_pcb
	(version 20241229)
	(generator "pcbnew")
	(generator_version "9.0")
	(general
		(thickness 1.294)
		(legacy_teardrops no)
	)
	(paper "A3")
	(title_block
		(title "Kintex 410T devboard")
		(date "2024-04-03")
		(rev "1.1.2")
		(comment 9 "footprints 650-654 of 975")
	)
	(layers
		(0 "F.Cu" mixed)
		(4 "In1.Cu" power)
		(6 "In2.Cu" power)
		(8 "In3.Cu" mixed)
		(10 "In4.Cu" power)
		(12 "In5.Cu" mixed)
		(14 "In6.Cu" power)
		(16 "In7.Cu" mixed)
		(18 "In8.Cu" power)
		(2 "B.Cu" mixed)
		(9 "F.Adhes" user "F.Adhesive")
		(11 "B.Adhes" user "B.Adhesive")
		(13 "F.Paste" user)
		(15 "B.Paste" user)
		(5 "F.SilkS" user "F.Silkscreen")
		(7 "B.SilkS" user "B.Silkscreen")
		(1 "F.Mask" user)
		(3 "B.Mask" user)
		(17 "Dwgs.User" user "User.Drawings")
		(19 "Cmts.User" user "User.Comments")
		(21 "Eco1.User" user "User.Eco1")
		(23 "Eco2.User" user "User.Eco2")
		(25 "Edge.Cuts" user)
		(27 "Margin" user)
		(31 "F.CrtYd" user "F.Courtyard")
		(29 "B.CrtYd" user "B.Courtyard")
		(35 "F.Fab" user)
		(33 "B.Fab" user)
	)
	(footprint "antmicro-footprints:Nexperia_SOD128"
		(layer "B.Cu")
		(at 155 133.4 180)
		(property "Reference" "D32"
			(at -0.025 2.225 0)
			(layer "B.SilkS")
			(effects
				(font
					(size 0.7 0.7)
					(thickness 0.15)
				)
				(justify mirror)
			)
		)
		(property "Value" "PMEG3050EP,115"
			(at 0 -2.4765 0)
			(layer "B.Fab")
			(effects
				(font
					(size 1 1)
					(thickness 0.15)
				)
				(justify mirror)
			)
		)
		(property "Description" "Schottky Rectifier, 30 V, 5 A, Single, SOD-128, 2 Pins, 360 mV"
			(at 0 0 180)
			(layer "F.Fab")
			(hide yes)
			(effects
				(font
					(size 1.27 1.27)
					(thickness 0.15)
				)
			)
		)
		(property "Author" "Antmicro"
			(at 310 266.8 0)
			(layer "B.Fab")
			(hide yes)
			(effects
				(font
					(size 1 1)
					(thickness 0.15)
				)
				(justify mirror)
			)
		)
		(property "DNP" "DNP"
			(at 310 266.8 0)
			(layer "B.Fab")
			(hide yes)
			(effects
				(font
					(size 1 1)
					(thickness 0.15)
				)
				(justify mirror)
			)
		)
		(property "License" "Apache-2.0"
			(at 310 266.8 0)
			(layer "B.Fab")
			(hide yes)
			(effects
				(font
					(size 1 1)
					(thickness 0.15)
				)
				(justify mirror)
			)
		)
		(property "MPN" "PMEG3050EP,115"
			(at 310 266.8 0)
			(layer "B.Fab")
			(hide yes)
			(effects
				(font
					(size 1 1)
					(thickness 0.15)
				)
				(justify mirror)
			)
		)
		(property "Manufacturer" "Nexperia"
			(at 310 266.8 0)
			(layer "B.Fab")
			(hide yes)
			(effects
				(font
					(size 1 1)
					(thickness 0.15)
				)
				(justify mirror)
			)
		)
		(property "dnp" ""
			(at 310 266.8 0)
			(layer "B.Fab")
			(hide yes)
			(effects
				(font
					(size 1 1)
					(thickness 0.15)
				)
				(justify mirror)
			)
		)
		(property "exclude_from_bom" ""
			(at 310 266.8 0)
			(layer "B.Fab")
			(hide yes)
			(effects
				(font
					(size 1 1)
					(thickness 0.15)
				)
				(justify mirror)
			)
		)
		(sheetname "FMC+ HSPC")
		(sheetfile "fmc-hspc.kicad_sch")
		(attr smd exclude_from_bom)
		(fp_line
			(start 2.12 1.474)
			(end -2.121 1.474)
			(stroke
				(width 0.15)
				(type solid)
			)
			(layer "B.SilkS")
		)
		(fp_line
			(start 2.12 1.287)
			(end 2.12 1.474)
			(stroke
				(width 0.15)
				(type solid)
			)
			(layer "B.SilkS")
		)
		(fp_line
			(start 2.12 -1.473)
			(end 2.12 -1.284)
			(stroke
				(width 0.15)
				(type solid)
			)
			(layer "B.SilkS")
		)
		(fp_line
			(start -1.6 1.4)
			(end -1.6 -1.4)
			(stroke
				(width 0.12)
				(type solid)
			)
			(layer "B.SilkS")
		)
		(fp_line
			(start -2.121 1.474)
			(end -2.121 1.287)
			(stroke
				(width 0.15)
				(type solid)
			)
			(layer "B.SilkS")
		)
		(fp_line
			(start -2.121 -1.284)
			(end -2.121 -1.473)
			(stroke
				(width 0.15)
				(type solid)
			)
			(layer "B.SilkS")
		)
		(fp_line
			(start -2.121 -1.473)
			(end 2.12 -1.473)
			(stroke
				(width 0.15)
				(type solid)
			)
			(layer "B.SilkS")
		)
		(fp_rect
			(start -2.8 1.6)
			(end 2.8 -1.6)
			(stroke
				(width 0.05)
				(type solid)
			)
			(fill no)
			(layer "B.CrtYd")
		)
		(fp_line
			(start 2.5 0.954)
			(end 1.993 0.954)
			(stroke
				(width 0.15)
				(type solid)
			)
			(layer "B.Fab")
		)
		(fp_line
			(start 2.5 -0.952)
			(end 2.5 0.954)
			(stroke
				(width 0.15)
				(type solid)
			)
			(layer "B.Fab")
		)
		(fp_line
			(start 1.993 1.347)
			(end -1.994 1.347)
			(stroke
				(width 0.15)
				(type solid)
			)
			(layer "B.Fab")
		)
		(fp_line
			(start 1.993 0.954)
			(end 1.993 -0.952)
			(stroke
				(width 0.15)
				(type solid)
			)
			(layer "B.Fab")
		)
		(fp_line
			(start 1.993 -0.952)
			(end 2.5 -0.952)
			(stroke
				(width 0.15)
				(type solid)
			)
			(layer "B.Fab")
		)
		(fp_line
			(start 1.993 -1.346)
			(end 1.993 1.347)
			(stroke
				(width 0.15)
				(type solid)
			)
			(layer "B.Fab")
		)
		(fp_line
			(start -1.994 1.347)
			(end -1.994 -1.346)
			(stroke
				(width 0.15)
				(type solid)
			)
			(layer "B.Fab")
		)
		(fp_line
			(start -1.994 0.954)
			(end -2.503 0.954)
			(stroke
				(width 0.15)
				(type solid)
			)
			(layer "B.Fab")
		)
		(fp_line
			(start -1.994 0.675)
			(end -1.321 1.347)
			(stroke
				(width 0.15)
				(type solid)
			)
			(layer "B.Fab")
		)
		(fp_line
			(start -1.994 -0.673)
			(end -1.321 -1.346)
			(stroke
				(width 0.15)
				(type solid)
			)
			(layer "B.Fab")
		)
		(fp_line
			(start -1.994 -0.952)
			(end -1.994 0.954)
			(stroke
				(width 0.15)
				(type solid)
			)
			(layer "B.Fab")
		)
		(fp_line
			(start -1.994 -1.346)
			(end 1.993 -1.346)
			(stroke
				(width 0.15)
				(type solid)
			)
			(layer "B.Fab")
		)
		(fp_line
			(start -2.503 0.954)
			(end -2.503 -0.952)
			(stroke
				(width 0.15)
				(type solid)
			)
			(layer "B.Fab")
		)
		(fp_line
			(start -2.503 -0.952)
			(end -1.994 -0.952)
			(stroke
				(width 0.15)
				(type solid)
			)
			(layer "B.Fab")
		)
		(pad "1" smd rect
			(at -2.298 0 180)
			(size 0.8096 1.905)
			(layers "B.Cu" "B.Mask" "B.Paste")
			(net 59 "12P0V")
			(pinfunction "1")
			(pintype "passive")
		)
		(pad "2" smd rect
			(at 2.297 0 180)
			(size 0.8096 1.905)
			(layers "B.Cu" "B.Mask" "B.Paste")
			(net 702 "VDC")
			(pinfunction "2")
			(pintype "passive")
		)
	)
	(footprint "antmicro-footprints:R_0402_1005Metric"
		(layer "B.Cu")
		(at 164 141.925 -90)
		(descr "Resistor SMD 0402")
		(tags "resistor SMD 0402")
		(property "Reference" "R34"
			(at -1.125 -1.275 90)
			(layer "B.SilkS")
			(effects
				(font
					(size 0.7 0.7)
					(thickness 0.15)
				)
				(justify left bottom mirror)
			)
		)
		(property "Value" "R_10k_0402"
			(at 0 -1.4 90)
			(layer "B.Fab")
			(effects
				(font
					(size 0.7 0.7)
					(thickness 0.15)
				)
				(justify left bottom mirror)
			)
		)
		(property "Description" "SMD Chip Resistor, 10 kohm, ± 1%, 62.5 mW, 0402 [1005 Metric], Thick Film, General Purpose"
			(at 0 0 270)
			(layer "F.Fab")
			(hide yes)
			(effects
				(font
					(size 1.27 1.27)
					(thickness 0.15)
				)
			)
		)
		(property "Author" "Antmicro"
			(at 22.075 305.925 0)
			(layer "B.Fab")
			(hide yes)
			(effects
				(font
					(size 1 1)
					(thickness 0.15)
				)
				(justify mirror)
			)
		)
		(property "License" "Apache-2.0"
			(at 22.075 305.925 0)
			(layer "B.Fab")
			(hide yes)
			(effects
				(font
					(size 1 1)
					(thickness 0.15)
				)
				(justify mirror)
			)
		)
		(property "MPN" "CR0402-FX-1002GLF"
			(at 22.075 305.925 0)
			(layer "B.Fab")
			(hide yes)
			(effects
				(font
					(size 1 1)
					(thickness 0.15)
				)
				(justify mirror)
			)
		)
		(property "Manufacturer" "Bourns"
			(at 22.075 305.925 0)
			(layer "B.Fab")
			(hide yes)
			(effects
				(font
					(size 1 1)
					(thickness 0.15)
				)
				(justify mirror)
			)
		)
		(property "Tolerance" "1%"
			(at 22.075 305.925 0)
			(layer "B.Fab")
			(hide yes)
			(effects
				(font
					(size 1 1)
					(thickness 0.15)
				)
				(justify mirror)
			)
		)
		(property "Val" "10k"
			(at 22.075 305.925 0)
			(layer "B.Fab")
			(hide yes)
			(effects
				(font
					(size 1 1)
					(thickness 0.15)
				)
				(justify mirror)
			)
		)
		(sheetname "DRAM + SRAM")
		(sheetfile "ram.kicad_sch")
		(attr smd)
		(fp_rect
			(start -0.925 0.47)
			(end 0.925 -0.47)
			(stroke
				(width 0.05)
				(type default)
			)
			(fill no)
			(layer "B.CrtYd")
		)
		(fp_rect
			(start -0.5 0.25)
			(end 0.5 -0.25)
			(stroke
				(width 0.15)
				(type solid)
			)
			(fill no)
			(layer "B.Fab")
		)
		(pad "1" smd roundrect
			(at -0.48 0 270)
			(size 0.59 0.64)
			(layers "B.Cu" "B.Mask" "B.Paste")
			(roundrect_rratio 0.25)
			(net 1 "GND")
			(pintype "passive")
		)
		(pad "2" smd roundrect
			(at 0.48 0 270)
			(size 0.59 0.64)
			(layers "B.Cu" "B.Mask" "B.Paste")
			(roundrect_rratio 0.25)
			(net 554 "/DRAM + SRAM/DDR.~{RESET}")
			(pintype "passive")
		)
	)
	(footprint "antmicro-footprints:QFN-2L_1.6x1x0.55mm"
		(layer "B.Cu")
		(at 264.75 88.6 90)
		(property "Reference" "D37"
			(at -2.2 -0.75 90)
			(layer "B.SilkS")
			(effects
				(font
					(size 0.7 0.7)
					(thickness 0.15)
				)
				(justify right bottom mirror)
			)
		)
		(property "Value" "ESDA25P35-1U1M"
			(at 0 -1.7 90)
			(layer "B.Fab")
			(effects
				(font
					(size 0.7 0.7)
					(thickness 0.15)
				)
				(justify right bottom mirror)
			)
		)
		(property "Description" "Unidirectional TVS, 30 kV, QFN-2L, 22 V, 195 pF"
			(at 0 0 90)
			(layer "F.Fab")
			(hide yes)
			(effects
				(font
					(size 1.27 1.27)
					(thickness 0.15)
				)
			)
		)
		(property "Author" "Antmicro"
			(at 353.35 -176.15 0)
			(layer "B.Fab")
			(hide yes)
			(effects
				(font
					(size 1 1)
					(thickness 0.15)
				)
				(justify mirror)
			)
		)
		(property "License" "Apache-2.0"
			(at 353.35 -176.15 0)
			(layer "B.Fab")
			(hide yes)
			(effects
				(font
					(size 1 1)
					(thickness 0.15)
				)
				(justify mirror)
			)
		)
		(property "MPN" "ESDA25P35-1U1M"
			(at 353.35 -176.15 0)
			(layer "B.Fab")
			(hide yes)
			(effects
				(font
					(size 1 1)
					(thickness 0.15)
				)
				(justify mirror)
			)
		)
		(property "Manufacturer" "STMicroelectronics"
			(at 353.35 -176.15 0)
			(layer "B.Fab")
			(hide yes)
			(effects
				(font
					(size 1 1)
					(thickness 0.15)
				)
				(justify mirror)
			)
		)
		(property "Public" "False"
			(at 353.35 -176.15 0)
			(layer "B.Fab")
			(hide yes)
			(effects
				(font
					(size 1 1)
					(thickness 0.15)
				)
				(justify mirror)
			)
		)
		(sheetname "User GPIO + LED + button + DIP switch")
		(sheetfile "user-gpio.kicad_sch")
		(attr smd)
		(fp_line
			(start 0.27 -0.3)
			(end -0.27 -0.3)
			(stroke
				(width 0.15)
				(type solid)
			)
			(layer "B.SilkS")
		)
		(fp_line
			(start 0.27 0.3)
			(end -0.27 0.3)
			(stroke
				(width 0.15)
				(type solid)
			)
			(layer "B.SilkS")
		)
		(fp_line
			(start -1.2 0.4)
			(end -1.2 -0.4)
			(stroke
				(width 0.15)
				(type solid)
			)
			(layer "B.SilkS")
		)
		(fp_rect
			(start 1.25 -0.65)
			(end -1.25 0.65)
			(stroke
				(width 0.05)
				(type solid)
			)
			(fill no)
			(layer "B.CrtYd")
		)
		(fp_line
			(start 0.201 -0.2)
			(end 0.201 0)
			(stroke
				(width 0.15)
				(type solid)
			)
			(layer "B.Fab")
		)
		(fp_line
			(start -0.199 -0.2)
			(end -0.199 -0.1)
			(stroke
				(width 0.15)
				(type solid)
			)
			(layer "B.Fab")
		)
		(fp_line
			(start 0.599 0)
			(end 0.201 0)
			(stroke
				(width 0.15)
				(type solid)
			)
			(layer "B.Fab")
		)
		(fp_line
			(start 0.201 0)
			(end 0.201 0.202)
			(stroke
				(width 0.15)
				(type solid)
			)
			(layer "B.Fab")
		)
		(fp_line
			(start -0.101 0)
			(end 0.201 -0.2)
			(stroke
				(width 0.15)
				(type solid)
			)
			(layer "B.Fab")
		)
		(fp_line
			(start -0.199 0)
			(end -0.597 0)
			(stroke
				(width 0.15)
				(type solid)
			)
			(layer "B.Fab")
		)
		(fp_line
			(start 0.201 0.202)
			(end -0.101 0)
			(stroke
				(width 0.15)
				(type solid)
			)
			(layer "B.Fab")
		)
		(fp_line
			(start -0.199 0.202)
			(end -0.199 -0.1)
			(stroke
				(width 0.15)
				(type solid)
			)
			(layer "B.Fab")
		)
		(fp_rect
			(start 0.848 -0.4)
			(end -0.85 0.402)
			(stroke
				(width 0.15)
				(type solid)
			)
			(fill no)
			(layer "B.Fab")
		)
		(pad "1" smd roundrect
			(at -0.7 0 270)
			(size 0.8 1)
			(layers "B.Cu" "B.Mask" "B.Paste")
			(roundrect_rratio 0.2)
			(net 1233 "/USER_IO.BUTTON2")
			(pinfunction "C")
			(pintype "passive")
		)
		(pad "2" smd roundrect
			(at 0.7 0 270)
			(size 0.8 1)
			(layers "B.Cu" "B.Mask" "B.Paste")
			(roundrect_rratio 0.2)
			(net 1 "GND")
			(pinfunction "A")
			(pintype "passive")
		)
	)
	(footprint "antmicro-footprints:R_Array_4x0201_Panasonic_EXB18V"
		(layer "B.Cu")
		(at 253.901 149.15)
		(property "Reference" "R33"
			(at 1.049 -0.725 0)
			(layer "B.SilkS")
			(effects
				(font
					(size 0.7 0.7)
					(thickness 0.15)
				)
				(justify left bottom mirror)
			)
		)
		(property "Value" "R_4x33R_0201_array"
			(at -1.1 -1.8 0)
			(layer "B.Fab")
			(effects
				(font
					(size 0.7 0.7)
					(thickness 0.15)
				)
				(justify right bottom mirror)
			)
		)
		(property "Description" "Fixed Network Resistor, 33 ohm, Isolated, 4 Resistors, 0502 [1406 Metric], Flat, ± 5%"
			(at 0 0 0)
			(layer "F.Fab")
			(hide yes)
			(effects
				(font
					(size 1.27 1.27)
					(thickness 0.15)
				)
			)
		)
		(property "Author" "Antmicro"
			(at 0 0 0)
			(layer "B.Fab")
			(hide yes)
			(effects
				(font
					(size 1 1)
					(thickness 0.15)
				)
				(justify mirror)
			)
		)
		(property "License" "Apache-2.0"
			(at 0 0 0)
			(layer "B.Fab")
			(hide yes)
			(effects
				(font
					(size 1 1)
					(thickness 0.15)
				)
				(justify mirror)
			)
		)
		(property "MPN" "EXB-18V330JX"
			(at 0 0 0)
			(layer "B.Fab")
			(hide yes)
			(effects
				(font
					(size 1 1)
					(thickness 0.15)
				)
				(justify mirror)
			)
		)
		(property "Manufacturer" "Panasonic"
			(at 0 0 0)
			(layer "B.Fab")
			(hide yes)
			(effects
				(font
					(size 1 1)
					(thickness 0.15)
				)
				(justify mirror)
			)
		)
		(property "Val" "R_4x33R_0201"
			(at 0 0 0)
			(layer "B.Fab")
			(hide yes)
			(effects
				(font
					(size 1 1)
					(thickness 0.15)
				)
				(justify mirror)
			)
		)
		(sheetname "Supervisior MCU")
		(sheetfile "supervisor-mcu.kicad_sch")
		(attr smd)
		(fp_line
			(start -0.8 0.45)
			(end -0.8 -0.45)
			(stroke
				(width 0.12)
				(type solid)
			)
			(layer "B.SilkS")
		)
		(fp_line
			(start 0.8 0.45)
			(end 0.8 -0.45)
			(stroke
				(width 0.12)
				(type solid)
			)
			(layer "B.SilkS")
		)
		(fp_rect
			(start -0.898 0.66)
			(end 0.898 -0.65)
			(stroke
				(width 0.05)
				(type solid)
			)
			(fill no)
			(layer "B.CrtYd")
		)
		(pad "1" smd roundrect
			(at -0.6 -0.298)
			(size 0.2 0.4)
			(layers "B.Cu" "B.Mask" "B.Paste")
			(roundrect_rratio 0.25)
			(net 1319 "/SUP_MCU.MISO")
			(pinfunction "R1.1")
			(pintype "passive")
		)
		(pad "2" smd roundrect
			(at -0.202 -0.298)
			(size 0.2 0.4)
			(layers "B.Cu" "B.Mask" "B.Paste")
			(roundrect_rratio 0.25)
			(net 1325 "/SUP_MCU.~{SCS}")
			(pinfunction "R2.1")
			(pintype "passive")
		)
		(pad "3" smd roundrect
			(at 0.2 -0.298)
			(size 0.2 0.4)
			(layers "B.Cu" "B.Mask" "B.Paste")
			(roundrect_rratio 0.25)
			(net 1323 "/SUP_MCU.SCLK0")
			(pinfunction "R3.1")
			(pintype "passive")
		)
		(pad "4" smd roundrect
			(at 0.598 -0.298)
			(size 0.2 0.4)
			(layers "B.Cu" "B.Mask" "B.Paste")
			(roundrect_rratio 0.25)
			(net 1379 "/SUP_MCU.D2")
			(pinfunction "R4.1")
			(pintype "passive")
		)
		(pad "5" smd roundrect
			(at 0.598 0.3)
			(size 0.2 0.4)
			(layers "B.Cu" "B.Mask" "B.Paste")
			(roundrect_rratio 0.25)
			(net 1097 "/Supervisior MCU/USB_D2")
			(pinfunction "R4.2")
			(pintype "passive")
		)
		(pad "6" smd roundrect
			(at 0.2 0.3)
			(size 0.2 0.4)
			(layers "B.Cu" "B.Mask" "B.Paste")
			(roundrect_rratio 0.25)
			(net 1089 "/Supervisior MCU/USB_SPI_SCK")
			(pinfunction "R3.2")
			(pintype "passive")
		)
		(pad "7" smd roundrect
			(at -0.202 0.3)
			(size 0.2 0.4)
			(layers "B.Cu" "B.Mask" "B.Paste")
			(roundrect_rratio 0.25)
			(net 1096 "/Supervisior MCU/USB_SPI_CS")
			(pinfunction "R2.2")
			(pintype "passive")
		)
		(pad "8" smd roundrect
			(at -0.6 0.3)
			(size 0.2 0.4)
			(layers "B.Cu" "B.Mask" "B.Paste")
			(roundrect_rratio 0.25)
			(net 1091 "/Supervisior MCU/USB_SPI_CIPO")
			(pinfunction "R1.2")
			(pintype "passive")
		)
	)
	(footprint "antmicro-footprints:C_0402_1005Metric"
		(layer "B.Cu")
		(at 183.2 142.2)
		(descr "Capacitor SMD 0402")
		(tags "capacitor SMD 0402")
		(property "Reference" "C85"
			(at 1.125 1.225 180)
			(layer "B.SilkS")
			(effects
				(font
					(size 0.7 0.7)
					(thickness 0.15)
				)
				(justify left bottom mirror)
			)
		)
		(property "Value" "C_100n_0402"
			(at 0 -1.169 180)
			(layer "B.Fab")
			(effects
				(font
					(size 0.7 0.7)
					(thickness 0.15)
				)
				(justify left bottom mirror)
			)
		)
		(property "Description" "SMD Multilayer Ceramic Capacitor, 0.1 µF, 50 V, 0402 [1005 Metric], ± 10%, X5R, GRM Series"
			(at 0 0 0)
			(layer "F.Fab")
			(hide yes)
			(effects
				(font
					(size 1.27 1.27)
					(thickness 0.15)
				)
			)
		)
		(property "Author" "Antmicro"
			(at 0 0 0)
			(layer "B.Fab")
			(hide yes)
			(effects
				(font
					(size 1 1)
					(thickness 0.15)
				)
				(justify mirror)
			)
		)
		(property "Dielectric" "X5R"
			(at 0 0 0)
			(layer "B.Fab")
			(hide yes)
			(effects
				(font
					(size 1 1)
					(thickness 0.15)
				)
				(justify mirror)
			)
		)
		(property "License" "Apache-2.0"
			(at 0 0 0)
			(layer "B.Fab")
			(hide yes)
			(effects
				(font
					(size 1 1)
					(thickness 0.15)
				)
				(justify mirror)
			)
		)
		(property "MPN" "GRM155R61H104KE14D"
			(at 0 0 0)
			(layer "B.Fab")
			(hide yes)
			(effects
				(font
					(size 1 1)
					(thickness 0.15)
				)
				(justify mirror)
			)
		)
		(property "Manufacturer" "Murata"
			(at 0 0 0)
			(layer "B.Fab")
			(hide yes)
			(effects
				(font
					(size 1 1)
					(thickness 0.15)
				)
				(justify mirror)
			)
		)
		(property "Val" "100n"
			(at 0 0 0)
			(layer "B.Fab")
			(hide yes)
			(effects
				(font
					(size 1 1)
					(thickness 0.15)
				)
				(justify mirror)
			)
		)
		(property "Voltage" "50V"
			(at 0 0 0)
			(layer "B.Fab")
			(hide yes)
			(effects
				(font
					(size 1 1)
					(thickness 0.15)
				)
				(justify mirror)
			)
		)
		(sheetname "FPGA Bank 33 & 34")
		(sheetfile "fpga-bank-33-34.kicad_sch")
		(attr smd)
		(fp_rect
			(start -0.925 0.47)
			(end 0.925 -0.47)
			(stroke
				(width 0.05)
				(type default)
			)
			(fill no)
			(layer "B.CrtYd")
		)
		(fp_line
			(start -0.494 -0.248)
			(end -0.494 0.25)
			(stroke
				(width 0.15)
				(type solid)
			)
			(layer "B.Fab")
		)
		(fp_line
			(start -0.494 0.25)
			(end 0.504 0.25)
			(stroke
				(width 0.15)
				(type solid)
			)
			(layer "B.Fab")
		)
		(fp_line
			(start 0.504 -0.248)
			(end -0.494 -0.248)
			(stroke
				(width 0.15)
				(type solid)
			)
			(layer "B.Fab")
		)
		(fp_line
			(start 0.504 0.25)
			(end 0.504 -0.248)
			(stroke
				(width 0.15)
				(type solid)
			)
			(layer "B.Fab")
		)
		(pad "1" smd roundrect
			(at -0.48 0)
			(size 0.59 0.64)
			(layers "B.Cu" "B.Mask" "B.Paste")
			(roundrect_rratio 0.25)
			(net 1 "GND")
			(pintype "passive")
		)
		(pad "2" smd roundrect
			(at 0.48 0)
			(size 0.59 0.64)
			(layers "B.Cu" "B.Mask" "B.Paste")
			(roundrect_rratio 0.25)
			(net 25 "+1V35")
			(pintype "passive")
		)
	)
)
